(kicad_pcb
	(version 20241229)
	(generator "pcbnew")
	(generator_version "9.0")
	(general
		(thickness 1.599998)
		(legacy_teardrops no)
	)
	(paper "A4")
	(title_block
		(title "Artix - Datacenter Secure Control Module (DC-SCM)")
		(date "2024-11-06")
		(rev "1.1.3")
		(comment 9 "footprint 134 of 544 (U1), pads 86-100 of 100")
	)
	(layers
		(0 "F.Cu" signal)
		(4 "In1.Cu" signal)
		(6 "In2.Cu" signal)
		(8 "In3.Cu" signal)
		(10 "In4.Cu" signal)
		(12 "In5.Cu" signal)
		(14 "In6.Cu" signal)
		(2 "B.Cu" signal)
		(9 "F.Adhes" user "F.Adhesive")
		(11 "B.Adhes" user "B.Adhesive")
		(13 "F.Paste" user)
		(15 "B.Paste" user)
		(5 "F.SilkS" user "F.Silkscreen")
		(7 "B.SilkS" user "B.Silkscreen")
		(1 "F.Mask" user)
		(3 "B.Mask" user)
		(17 "Dwgs.User" user "User.Drawings")
		(19 "Cmts.User" user "User.Comments")
		(21 "Eco1.User" user "User.Eco1")
		(23 "Eco2.User" user "User.Eco2")
		(25 "Edge.Cuts" user)
		(27 "Margin" user)
		(31 "F.CrtYd" user "F.Courtyard")
		(29 "B.CrtYd" user "B.Courtyard")
		(35 "F.Fab" user)
		(33 "B.Fab" user)
	)
	(footprint "antmicro-footprints:BGA-170-100_18x14mm_Layout17x10_P1mm"
		(layer "F.Cu")
		(at 138.774 125.014 180)
		(descr "Uses depopulated JEDEC-MO-304B")
		(property "Reference" "U1"
			(at 6.974 9.314 180)
			(layer "F.SilkS")
			(effects
				(font
					(size 0.7 0.7)
					(thickness 0.15)
				)
				(justify left bottom)
			)
		)
		(property "Value" "MTFC16GAPALNA-AIT"
			(at 16.305 13.334 180)
			(layer "F.Fab")
			(effects
				(font
					(size 0.7 0.7)
					(thickness 0.15)
				)
				(justify left bottom)
			)
		)
		(property "Datasheet" "https://www.mouser.com/datasheet/2/671/micron_technology_mict-s-a0006806196-1-1759129.pdf"
			(at 0 0 180)
			(layer "F.Fab")
			(hide yes)
			(effects
				(font
					(size 1.27 1.27)
					(thickness 0.15)
				)
			)
		)
		(property "Description" "Managed NAND Flash Serial e-MMC 3.3V 128G-bit 128G/32G/16G x 1/4-bit/8-bit Automotive AEC-Q100 100-Pin TBGA Tray"
			(at 0 0 180)
			(layer "F.Fab")
			(hide yes)
			(effects
				(font
					(size 1.27 1.27)
					(thickness 0.15)
				)
			)
		)
		(property "Author" "Antmicro"
			(at 277.548 250.028 0)
			(layer "F.Fab")
			(hide yes)
			(effects
				(font
					(size 1 1)
					(thickness 0.15)
				)
			)
		)
		(property "License" "Apache-2.0"
			(at 277.548 250.028 0)
			(layer "F.Fab")
			(hide yes)
			(effects
				(font
					(size 1 1)
					(thickness 0.15)
				)
			)
		)
		(property "MPN" "MTFC16GAPALNA-AIT"
			(at 277.548 250.028 0)
			(layer "F.Fab")
			(hide yes)
			(effects
				(font
					(size 1 1)
					(thickness 0.15)
				)
			)
		)
		(property "Manufacturer" "Micron Technology"
			(at 277.548 250.028 0)
			(layer "F.Fab")
			(hide yes)
			(effects
				(font
					(size 1 1)
					(thickness 0.15)
				)
			)
		)
		(sheetname "/Interfaces/")
		(sheetfile "interfaces.kicad_sch")
		(attr smd)
		(pad "N9" smd circle
			(at 3.499 3.999 180)
			(size 0.37 0.37)
			(layers "F.Cu" "F.Mask" "F.Paste")
			(net 327 "MMC_DAT6")
			(pinfunction "DAT6")
			(pintype "bidirectional")
		)
		(pad "P2" smd circle
			(at -3.5 4.999 180)
			(size 0.37 0.37)
			(layers "F.Cu" "F.Mask" "F.Paste")
			(net 1 "GND")
			(pinfunction "VSSQ")
			(pintype "passive")
		)
		(pad "P3" smd circle
			(at -2.5 4.999 180)
			(size 0.37 0.37)
			(layers "F.Cu" "F.Mask" "F.Paste")
			(net 2 "VCC3V3")
			(pinfunction "VCCQ")
			(pintype "passive")
		)
		(pad "P4" smd circle
			(at -1.5 4.999 180)
			(size 0.37 0.37)
			(layers "F.Cu" "F.Mask" "F.Paste")
			(net 513 "unconnected-(U1-RFU-PadP4)")
			(pinfunction "RFU")
			(pintype "no_connect")
		)
		(pad "P5" smd circle
			(at -0.5 4.999 180)
			(size 0.37 0.37)
			(layers "F.Cu" "F.Mask" "F.Paste")
			(net 329 "MMC_CMD")
			(pinfunction "CMD")
			(pintype "bidirectional")
		)
		(pad "P6" smd circle
			(at 0.499 4.999 180)
			(size 0.37 0.37)
			(layers "F.Cu" "F.Mask" "F.Paste")
			(net 306 "Net-(U1-CLK)")
			(pinfunction "CLK")
			(pintype "input")
		)
		(pad "P7" smd circle
			(at 1.499 4.999 180)
			(size 0.37 0.37)
			(layers "F.Cu" "F.Mask" "F.Paste")
			(net 514 "unconnected-(U1-RFU-PadP7)")
			(pinfunction "RFU")
			(pintype "no_connect")
		)
		(pad "P8" smd circle
			(at 2.499 4.999 180)
			(size 0.37 0.37)
			(layers "F.Cu" "F.Mask" "F.Paste")
			(net 2 "VCC3V3")
			(pinfunction "VCCQ")
			(pintype "passive")
		)
		(pad "P9" smd circle
			(at 3.499 4.999 180)
			(size 0.37 0.37)
			(layers "F.Cu" "F.Mask" "F.Paste")
			(net 1 "GND")
			(pinfunction "VSSQ")
			(pintype "passive")
		)
		(pad "T1" smd circle
			(at -4.5 6.998 180)
			(size 0.37 0.37)
			(layers "F.Cu" "F.Mask" "F.Paste")
			(net 515 "unconnected-(U1-NC-PadT1)")
			(pinfunction "NC")
			(pintype "no_connect")
		)
		(pad "T10" smd circle
			(at 4.499 6.998 180)
			(size 0.37 0.37)
			(layers "F.Cu" "F.Mask" "F.Paste")
			(net 516 "unconnected-(U1-NC-PadT10)")
			(pinfunction "NC")
			(pintype "no_connect")
		)
		(pad "U1" smd circle
			(at -4.5 7.998 180)
			(size 0.37 0.37)
			(layers "F.Cu" "F.Mask" "F.Paste")
			(net 517 "unconnected-(U1-NC-PadU1)")
			(pinfunction "NC")
			(pintype "no_connect")
		)
		(pad "U2" smd circle
			(at -3.5 7.998 180)
			(size 0.37 0.37)
			(layers "F.Cu" "F.Mask" "F.Paste")
			(net 518 "unconnected-(U1-NC-PadU2)")
			(pinfunction "NC")
			(pintype "no_connect")
		)
		(pad "U9" smd circle
			(at 3.499 7.998 180)
			(size 0.37 0.37)
			(layers "F.Cu" "F.Mask" "F.Paste")
			(net 519 "unconnected-(U1-NC-PadU9)")
			(pinfunction "NC")
			(pintype "no_connect")
		)
		(pad "U10" smd circle
			(at 4.499 7.998 180)
			(size 0.37 0.37)
			(layers "F.Cu" "F.Mask" "F.Paste")
			(net 520 "unconnected-(U1-NC-PadU10)")
			(pinfunction "NC")
			(pintype "no_connect")
		)
	)
)
